(kicad_pcb
	(version 20221018)
	(generator pcbnew)
	(general
    (thickness 1.586)
  )
	(paper "A4")
	(title_block
    (date "2024-03-26")
    (rev "1.1.3")
		(comment 9 "footprints 69-77 of 146")
	)
	(layers
    (0 "F.Cu" signal)
    (1 "In1.Cu" power)
    (2 "In2.Cu" power)
    (31 "B.Cu" signal)
    (32 "B.Adhes" user "B.Adhesive")
    (33 "F.Adhes" user "F.Adhesive")
    (34 "B.Paste" user)
    (35 "F.Paste" user)
    (36 "B.SilkS" user "B.Silkscreen")
    (37 "F.SilkS" user "F.Silkscreen")
    (38 "B.Mask" user)
    (39 "F.Mask" user)
    (40 "Dwgs.User" user "User.Drawings")
    (41 "Cmts.User" user "User.Comments")
    (42 "Eco1.User" user "User.Eco1")
    (43 "Eco2.User" user "User.Eco2")
    (44 "Edge.Cuts" user)
    (45 "Margin" user)
    (46 "B.CrtYd" user "B.Courtyard")
    (47 "F.CrtYd" user "F.Courtyard")
    (48 "B.Fab" user)
    (49 "F.Fab" user)
  )
	(footprint "scalenode-cm4-baseboard-footprints:LED_0603_1608Metric_G" (layer "F.Cu")
    (at 98.9 90.85)
    (descr "LED SMD 0603 Green")
    (tags "LED SMD 0603 Green")
    (property "Author" "Antmicro")
    (property "License" "Apache-2.0")
    (property "MPN" "KP-1608CGCK")
    (property "Manufacturer" "Kingbright")
    (property "Sheetfile" "poe.kicad_sch")
    (property "Sheetname" "PoE")
    (attr smd)
    (fp_text reference "D7" (at 1.35 0.425) (layer "F.SilkS")
        (effects (font (size 0.7 0.7) (thickness 0.15)) (justify left bottom))
    )
    (fp_text value "LED_G_0603_KP-1608CGCK" (at 0 1.6) (layer "F.Fab")
        (effects (font (size 0.7 0.7) (thickness 0.15)) (justify left bottom))
    )
    (fp_text user "Author: Antmicro" (at -1.31 4.769) (layer "F.Fab") hide
        (effects (font (size 0.7 0.7) (thickness 0.15)) (justify left bottom))
    )
    (fp_text user "${REFERENCE}" (at -1.31 3.769) (layer "F.Fab") hide
        (effects (font (size 0.7 0.7) (thickness 0.15)) (justify left bottom))
    )
    (fp_text user "License: Apache-2.0" (at -1.31 5.769) (layer "F.Fab") hide
        (effects (font (size 0.7 0.7) (thickness 0.15)) (justify left bottom))
    )
    (fp_line (start -0.27 -0.3) (end 0.27 -0.3)
      (stroke (width 0.15) (type solid)) (layer "F.SilkS"))
    (fp_line (start -0.27 0.3) (end 0.27 0.3)
      (stroke (width 0.15) (type solid)) (layer "F.SilkS"))
    (fp_line (start 1.25 0.5) (end 1.25 -0.498)
      (stroke (width 0.15) (type solid)) (layer "F.SilkS"))
    (fp_rect (start 1.31 0.7) (end -1.31 -0.7)
      (stroke (width 0.05) (type solid)) (fill none) (layer "F.CrtYd"))
    (fp_line (start -0.599 0) (end -0.201 0)
      (stroke (width 0.15) (type solid)) (layer "F.Fab"))
    (fp_line (start -0.201 -0.2) (end -0.201 0)
      (stroke (width 0.15) (type solid)) (layer "F.Fab"))
    (fp_line (start -0.201 0) (end -0.201 0.202)
      (stroke (width 0.15) (type solid)) (layer "F.Fab"))
    (fp_line (start -0.201 0.202) (end 0.101 0)
      (stroke (width 0.15) (type solid)) (layer "F.Fab"))
    (fp_line (start 0.101 0) (end -0.201 -0.2)
      (stroke (width 0.15) (type solid)) (layer "F.Fab"))
    (fp_line (start 0.199 -0.2) (end 0.199 -0.1)
      (stroke (width 0.15) (type solid)) (layer "F.Fab"))
    (fp_line (start 0.199 0) (end 0.597 0)
      (stroke (width 0.15) (type solid)) (layer "F.Fab"))
    (fp_line (start 0.199 0.202) (end 0.199 -0.1)
      (stroke (width 0.15) (type solid)) (layer "F.Fab"))
    (fp_rect (start -0.848 -0.4) (end 0.85 0.402)
      (stroke (width 0.15) (type solid)) (fill none) (layer "F.Fab"))
    (pad "1" smd rect (at -0.75 0 180) (size 0.8 0.8) (layers "F.Cu" "F.Paste" "F.Mask")
      (net 21 "Net-(D7-Pad1)") (pinfunction "1") (pintype "passive"))
    (pad "2" smd rect (at 0.75 0 180) (size 0.8 0.8) (layers "F.Cu" "F.Paste" "F.Mask")
      (net 4 "GNDD") (pinfunction "2") (pintype "passive"))
  )
	(footprint "scalenode-cm4-baseboard-footprints:R_0402_1005Metric" (layer "F.Cu")
    (at 93.3 95.1 180)
    (descr "Resistor SMD 0402")
    (tags "resistor SMD 0402")
    (property "Author" "Antmicro")
    (property "DNP" "DNP")
    (property "License" "Apache-2.0")
    (property "MPN" "CR0402-FX-1301GLF")
    (property "Manufacturer" "Bourns")
    (property "Sheetfile" "poe.kicad_sch")
    (property "Sheetname" "PoE")
    (property "Tolerance" "1%")
    (property "Val" "1k3")
    (property "dnp" "")
    (property "exclude_from_bom" "")
    (property "ki_description" "1k3 resistor in 0402 package with 1% tolerance")
    (attr exclude_from_pos_files exclude_from_bom)
    (fp_text reference "R37" (at 1.05 -1.35 180) (layer "F.SilkS")
        (effects (font (size 0.7 0.7) (thickness 0.15)) (justify left bottom))
    )
    (fp_text value "R_1k3_0402" (at 0 1.4 180) (layer "F.Fab")
        (effects (font (size 0.7 0.7) (thickness 0.15)) (justify left bottom))
    )
    (fp_text user "${REFERENCE}" (at -0.95 3.168 180) (layer "F.Fab") hide
        (effects (font (size 0.7 0.7) (thickness 0.15)) (justify left bottom))
    )
    (fp_text user "License: Apache-2.0" (at -0.95 5.169 180) (layer "F.Fab") hide
        (effects (font (size 0.7 0.7) (thickness 0.15)) (justify left bottom))
    )
    (fp_text user "Author: Antmicro" (at -0.95 4.169 180) (layer "F.Fab") hide
        (effects (font (size 0.7 0.7) (thickness 0.15)) (justify left bottom))
    )
    (fp_rect (start -0.95 -0.48) (end 0.95 0.48)
      (stroke (width 0.05) (type solid)) (fill none) (layer "F.CrtYd"))
    (fp_rect (start -0.5 -0.25) (end 0.5 0.25)
      (stroke (width 0.15) (type solid)) (fill none) (layer "F.Fab"))
    (pad "1" smd roundrect (at -0.485 0 180) (size 0.59 0.64) (layers "F.Cu" "F.Paste" "F.Mask") (roundrect_rratio 0.25)
      (net 5 "VSS") (pintype "passive"))
    (pad "2" smd roundrect (at 0.485 0 180) (size 0.59 0.64) (layers "F.Cu" "F.Paste" "F.Mask") (roundrect_rratio 0.25)
      (net 259 "Net-(U3-AMPS_CTL)") (pintype "passive"))
  )
	(footprint "scalenode-cm4-baseboard-footprints:C_2220_5650Metric" (layer "F.Cu")
    (at 110.4 85.96)
    (descr "Capacitor SMD 2220")
    (tags "capacitor SMD 2220")
    (property "Author" "Antmicro")
    (property "Dielectric" "X7S")
    (property "License" "Apache-2.0")
    (property "MPN" "C5750X7S2A226M280KB")
    (property "Manufacturer" "TDK")
    (property "Sheetfile" "poe.kicad_sch")
    (property "Sheetname" "PoE")
    (property "Val" "22u")
    (property "Voltage" "100V")
    (property "ki_description" " ")
    (attr smd)
    (fp_text reference "C32" (at -1.15 -3.2) (layer "F.SilkS")
        (effects (font (size 0.7 0.7) (thickness 0.15)) (justify left bottom))
    )
    (fp_text value "C_22u_100V_2220" (at 0 3.9) (layer "F.Fab")
        (effects (font (size 0.7 0.7) (thickness 0.15)) (justify left bottom))
    )
    (fp_text user "License: Apache-2.0" (at -3.7 6.9) (layer "F.Fab") hide
        (effects (font (size 0.7 0.7) (thickness 0.15)) (justify left bottom))
    )
    (fp_text user "Author: Antmicro" (at -3.7 7.9) (layer "F.Fab") hide
        (effects (font (size 0.7 0.7) (thickness 0.15)) (justify left bottom))
    )
    (fp_text user "${REFERENCE}" (at -3.7 5.9) (layer "F.Fab") hide
        (effects (font (size 0.7 0.7) (thickness 0.15)) (justify left bottom))
    )
    (fp_line (start -1.415 -2.61) (end 1.415 -2.61)
      (stroke (width 0.15) (type solid)) (layer "F.SilkS"))
    (fp_line (start -1.415 2.61) (end 1.415 2.61)
      (stroke (width 0.15) (type solid)) (layer "F.SilkS"))
    (fp_rect (start -3.7 -2.95) (end 3.7 2.95)
      (stroke (width 0.05) (type solid)) (fill none) (layer "F.CrtYd"))
    (fp_rect (start -2.85 -2.5) (end 2.85 2.5)
      (stroke (width 0.15) (type solid)) (fill none) (layer "F.Fab"))
    (pad "1" smd roundrect (at -2.55 0) (size 1.8 5.4) (layers "F.Cu" "F.Paste" "F.Mask") (roundrect_rratio 0.138889)
      (net 4 "GNDD") (pintype "passive"))
    (pad "2" smd roundrect (at 2.55 0) (size 1.8 5.4) (layers "F.Cu" "F.Paste" "F.Mask") (roundrect_rratio 0.138889)
      (net 6 "/PoE/VDD_POE_IN") (pintype "passive"))
  )
	(footprint "scalenode-cm4-baseboard-footprints:R_0603_1608Metric" (layer "F.Cu")
    (at 98.925 94.375 180)
    (descr "Resistor SMD 0603")
    (tags "resistor SMD 0603")
    (property "Author" "Antmicro")
    (property "License" "Apache-2.0")
    (property "MPN" "CR0603-FX-1502ELF")
    (property "Manufacturer" "Bourns")
    (property "Sheetfile" "poe.kicad_sch")
    (property "Sheetname" "PoE")
    (property "Tolerance" "1%")
    (property "Val" "15k")
    (property "ki_description" "15k resistor in 0603 package with 1% tolerance")
    (attr smd)
    (fp_text reference "R34" (at -1.15 -0.475 180) (layer "F.SilkS")
        (effects (font (size 0.7 0.7) (thickness 0.15)) (justify left bottom))
    )
    (fp_text value "R_15k_0603" (at 0 1.6 180) (layer "F.Fab")
        (effects (font (size 0.7 0.7) (thickness 0.15)) (justify left bottom))
    )
    (fp_text user "${REFERENCE}" (at -1.25 3.898 180) (layer "F.Fab") hide
        (effects (font (size 0.7 0.7) (thickness 0.15)) (justify left bottom))
    )
    (fp_text user "License: Apache-2.0" (at -1.25 5.9 180) (layer "F.Fab") hide
        (effects (font (size 0.7 0.7) (thickness 0.15)) (justify left bottom))
    )
    (fp_text user "Author: Antmicro" (at -1.25 4.9 180) (layer "F.Fab") hide
        (effects (font (size 0.7 0.7) (thickness 0.15)) (justify left bottom))
    )
    (fp_line (start -0.3 -0.3) (end 0.3 -0.3)
      (stroke (width 0.15) (type solid)) (layer "F.SilkS"))
    (fp_line (start -0.3 0.3) (end 0.3 0.3)
      (stroke (width 0.15) (type solid)) (layer "F.SilkS"))
    (fp_rect (start -1.25 -0.7) (end 1.25 0.7)
      (stroke (width 0.05) (type solid)) (fill none) (layer "F.CrtYd"))
    (fp_rect (start -0.8 -0.4) (end 0.8 0.4)
      (stroke (width 0.15) (type solid)) (fill none) (layer "F.Fab"))
    (pad "1" smd roundrect (at -0.7 0 180) (size 0.6 0.8) (layers "F.Cu" "F.Paste" "F.Mask") (roundrect_rratio 0.2)
      (net 4 "GNDD") (pintype "passive"))
    (pad "2" smd roundrect (at 0.7 0 180) (size 0.6 0.8) (layers "F.Cu" "F.Paste" "F.Mask") (roundrect_rratio 0.2)
      (net 6 "/PoE/VDD_POE_IN") (pintype "passive"))
  )
	(footprint "scalenode-cm4-baseboard-footprints:R_0402_1005Metric" (layer "B.Cu")
    (at 99.452 86.375 90)
    (descr "Resistor SMD 0402")
    (tags "resistor SMD 0402")
    (property "Author" "Antmicro")
    (property "License" "Apache-2.0")
    (property "MPN" "CR0402-FX-1002GLF")
    (property "Manufacturer" "Bourns")
    (property "Sheetfile" "interfaces.kicad_sch")
    (property "Sheetname" "Interfaces")
    (property "Tolerance" "1%")
    (property "Val" "10k")
    (property "ki_description" "10k resistor in 0402 package with 1% tolerance")
    (attr smd)
    (fp_text reference "R13" (at 3.2 0.403 270) (layer "B.SilkS")
        (effects (font (size 0.7 0.7) (thickness 0.15)) (justify left bottom mirror))
    )
    (fp_text value "R_10k_0402" (at 0 -1.4 270) (layer "B.Fab")
        (effects (font (size 0.7 0.7) (thickness 0.15)) (justify left bottom mirror))
    )
    (fp_text user "Author: Antmicro" (at -0.95 -4.169 270) (layer "B.Fab") hide
        (effects (font (size 0.7 0.7) (thickness 0.15)) (justify left bottom mirror))
    )
    (fp_text user "License: Apache-2.0" (at -0.95 -5.169 270) (layer "B.Fab") hide
        (effects (font (size 0.7 0.7) (thickness 0.15)) (justify left bottom mirror))
    )
    (fp_text user "${REFERENCE}" (at -0.95 -3.168 270) (layer "B.Fab") hide
        (effects (font (size 0.7 0.7) (thickness 0.15)) (justify left bottom mirror))
    )
    (fp_rect (start -0.95 0.48) (end 0.95 -0.48)
      (stroke (width 0.05) (type solid)) (fill none) (layer "B.CrtYd"))
    (fp_rect (start -0.5 0.25) (end 0.5 -0.25)
      (stroke (width 0.15) (type solid)) (fill none) (layer "B.Fab"))
    (pad "1" smd roundrect (at -0.485 0 90) (size 0.59 0.64) (layers "B.Cu" "B.Paste" "B.Mask") (roundrect_rratio 0.25)
      (net 232 "3V3_RPi") (pintype "passive"))
    (pad "2" smd roundrect (at 0.485 0 90) (size 0.59 0.64) (layers "B.Cu" "B.Paste" "B.Mask") (roundrect_rratio 0.25)
      (net 33 "SD_DAT2") (pintype "passive"))
  )
	(footprint "scalenode-cm4-baseboard-footprints:R_0402_1005Metric" (layer "B.Cu")
    (at 98.436 86.375 90)
    (descr "Resistor SMD 0402")
    (tags "resistor SMD 0402")
    (property "Author" "Antmicro")
    (property "License" "Apache-2.0")
    (property "MPN" "CR0402-FX-1002GLF")
    (property "Manufacturer" "Bourns")
    (property "Sheetfile" "interfaces.kicad_sch")
    (property "Sheetname" "Interfaces")
    (property "Tolerance" "1%")
    (property "Val" "10k")
    (property "ki_description" "10k resistor in 0402 package with 1% tolerance")
    (attr smd)
    (fp_text reference "R12" (at 3.2 0.403 270) (layer "B.SilkS")
        (effects (font (size 0.7 0.7) (thickness 0.15)) (justify left bottom mirror))
    )
    (fp_text value "R_10k_0402" (at 0 -1.4 270) (layer "B.Fab")
        (effects (font (size 0.7 0.7) (thickness 0.15)) (justify left bottom mirror))
    )
    (fp_text user "License: Apache-2.0" (at -0.95 -5.169 270) (layer "B.Fab") hide
        (effects (font (size 0.7 0.7) (thickness 0.15)) (justify left bottom mirror))
    )
    (fp_text user "Author: Antmicro" (at -0.95 -4.169 270) (layer "B.Fab") hide
        (effects (font (size 0.7 0.7) (thickness 0.15)) (justify left bottom mirror))
    )
    (fp_text user "${REFERENCE}" (at -0.95 -3.168 270) (layer "B.Fab") hide
        (effects (font (size 0.7 0.7) (thickness 0.15)) (justify left bottom mirror))
    )
    (fp_rect (start -0.95 0.48) (end 0.95 -0.48)
      (stroke (width 0.05) (type solid)) (fill none) (layer "B.CrtYd"))
    (fp_rect (start -0.5 0.25) (end 0.5 -0.25)
      (stroke (width 0.15) (type solid)) (fill none) (layer "B.Fab"))
    (pad "1" smd roundrect (at -0.485 0 90) (size 0.59 0.64) (layers "B.Cu" "B.Paste" "B.Mask") (roundrect_rratio 0.25)
      (net 232 "3V3_RPi") (pintype "passive"))
    (pad "2" smd roundrect (at 0.485 0 90) (size 0.59 0.64) (layers "B.Cu" "B.Paste" "B.Mask") (roundrect_rratio 0.25)
      (net 32 "SD_DAT3") (pintype "passive"))
  )
	(footprint "scalenode-cm4-baseboard-footprints:R_0402_1005Metric" (layer "B.Cu")
    (at 97.42 86.375 90)
    (descr "Resistor SMD 0402")
    (tags "resistor SMD 0402")
    (property "Author" "Antmicro")
    (property "License" "Apache-2.0")
    (property "MPN" "CR0402-FX-1002GLF")
    (property "Manufacturer" "Bourns")
    (property "Sheetfile" "interfaces.kicad_sch")
    (property "Sheetname" "Interfaces")
    (property "Tolerance" "1%")
    (property "Val" "10k")
    (property "ki_description" "10k resistor in 0402 package with 1% tolerance")
    (attr smd)
    (fp_text reference "R11" (at 3.2 0.403 270) (layer "B.SilkS")
        (effects (font (size 0.7 0.7) (thickness 0.15)) (justify left bottom mirror))
    )
    (fp_text value "R_10k_0402" (at 0 -1.4 270) (layer "B.Fab")
        (effects (font (size 0.7 0.7) (thickness 0.15)) (justify left bottom mirror))
    )
    (fp_text user "License: Apache-2.0" (at -0.95 -5.169 270) (layer "B.Fab") hide
        (effects (font (size 0.7 0.7) (thickness 0.15)) (justify left bottom mirror))
    )
    (fp_text user "Author: Antmicro" (at -0.95 -4.169 270) (layer "B.Fab") hide
        (effects (font (size 0.7 0.7) (thickness 0.15)) (justify left bottom mirror))
    )
    (fp_text user "${REFERENCE}" (at -0.95 -3.168 270) (layer "B.Fab") hide
        (effects (font (size 0.7 0.7) (thickness 0.15)) (justify left bottom mirror))
    )
    (fp_rect (start -0.95 0.48) (end 0.95 -0.48)
      (stroke (width 0.05) (type solid)) (fill none) (layer "B.CrtYd"))
    (fp_rect (start -0.5 0.25) (end 0.5 -0.25)
      (stroke (width 0.15) (type solid)) (fill none) (layer "B.Fab"))
    (pad "1" smd roundrect (at -0.485 0 90) (size 0.59 0.64) (layers "B.Cu" "B.Paste" "B.Mask") (roundrect_rratio 0.25)
      (net 232 "3V3_RPi") (pintype "passive"))
    (pad "2" smd roundrect (at 0.485 0 90) (size 0.59 0.64) (layers "B.Cu" "B.Paste" "B.Mask") (roundrect_rratio 0.25)
      (net 31 "SD_CMD") (pintype "passive"))
  )
	(footprint "scalenode-cm4-baseboard-footprints:R_0402_1005Metric" (layer "B.Cu")
    (at 96.404 86.375 90)
    (descr "Resistor SMD 0402")
    (tags "resistor SMD 0402")
    (property "Author" "Antmicro")
    (property "License" "Apache-2.0")
    (property "MPN" "CR0402-FX-1002GLF")
    (property "Manufacturer" "Bourns")
    (property "Sheetfile" "interfaces.kicad_sch")
    (property "Sheetname" "Interfaces")
    (property "Tolerance" "1%")
    (property "Val" "10k")
    (property "ki_description" "10k resistor in 0402 package with 1% tolerance")
    (attr smd)
    (fp_text reference "R10" (at 3.2 0.403 270) (layer "B.SilkS")
        (effects (font (size 0.7 0.7) (thickness 0.15)) (justify left bottom mirror))
    )
    (fp_text value "R_10k_0402" (at 0 -1.4 270) (layer "B.Fab")
        (effects (font (size 0.7 0.7) (thickness 0.15)) (justify left bottom mirror))
    )
    (fp_text user "License: Apache-2.0" (at -0.95 -5.169 270) (layer "B.Fab") hide
        (effects (font (size 0.7 0.7) (thickness 0.15)) (justify left bottom mirror))
    )
    (fp_text user "Author: Antmicro" (at -0.95 -4.169 270) (layer "B.Fab") hide
        (effects (font (size 0.7 0.7) (thickness 0.15)) (justify left bottom mirror))
    )
    (fp_text user "${REFERENCE}" (at -0.95 -3.168 270) (layer "B.Fab") hide
        (effects (font (size 0.7 0.7) (thickness 0.15)) (justify left bottom mirror))
    )
    (fp_rect (start -0.95 0.48) (end 0.95 -0.48)
      (stroke (width 0.05) (type solid)) (fill none) (layer "B.CrtYd"))
    (fp_rect (start -0.5 0.25) (end 0.5 -0.25)
      (stroke (width 0.15) (type solid)) (fill none) (layer "B.Fab"))
    (pad "1" smd roundrect (at -0.485 0 90) (size 0.59 0.64) (layers "B.Cu" "B.Paste" "B.Mask") (roundrect_rratio 0.25)
      (net 232 "3V3_RPi") (pintype "passive"))
    (pad "2" smd roundrect (at 0.485 0 90) (size 0.59 0.64) (layers "B.Cu" "B.Paste" "B.Mask") (roundrect_rratio 0.25)
      (net 30 "SD_CLK") (pintype "passive"))
  )
	(footprint "scalenode-cm4-baseboard-footprints:R_0402_1005Metric" (layer "B.Cu")
    (at 95.388 86.375 90)
    (descr "Resistor SMD 0402")
    (tags "resistor SMD 0402")
    (property "Author" "Antmicro")
    (property "License" "Apache-2.0")
    (property "MPN" "CR0402-FX-1002GLF")
    (property "Manufacturer" "Bourns")
    (property "Sheetfile" "interfaces.kicad_sch")
    (property "Sheetname" "Interfaces")
    (property "Tolerance" "1%")
    (property "Val" "10k")
    (property "ki_description" "10k resistor in 0402 package with 1% tolerance")
    (attr smd)
    (fp_text reference "R9" (at 3.2 0.403 270) (layer "B.SilkS")
        (effects (font (size 0.7 0.7) (thickness 0.15)) (justify left bottom mirror))
    )
    (fp_text value "R_10k_0402" (at 0 -1.4 270) (layer "B.Fab")
        (effects (font (size 0.7 0.7) (thickness 0.15)) (justify left bottom mirror))
    )
    (fp_text user "Author: Antmicro" (at -0.95 -4.169 270) (layer "B.Fab") hide
        (effects (font (size 0.7 0.7) (thickness 0.15)) (justify left bottom mirror))
    )
    (fp_text user "License: Apache-2.0" (at -0.95 -5.169 270) (layer "B.Fab") hide
        (effects (font (size 0.7 0.7) (thickness 0.15)) (justify left bottom mirror))
    )
    (fp_text user "${REFERENCE}" (at -0.95 -3.168 270) (layer "B.Fab") hide
        (effects (font (size 0.7 0.7) (thickness 0.15)) (justify left bottom mirror))
    )
    (fp_rect (start -0.95 0.48) (end 0.95 -0.48)
      (stroke (width 0.05) (type solid)) (fill none) (layer "B.CrtYd"))
    (fp_rect (start -0.5 0.25) (end 0.5 -0.25)
      (stroke (width 0.15) (type solid)) (fill none) (layer "B.Fab"))
    (pad "1" smd roundrect (at -0.485 0 90) (size 0.59 0.64) (layers "B.Cu" "B.Paste" "B.Mask") (roundrect_rratio 0.25)
      (net 232 "3V3_RPi") (pintype "passive"))
    (pad "2" smd roundrect (at 0.485 0 90) (size 0.59 0.64) (layers "B.Cu" "B.Paste" "B.Mask") (roundrect_rratio 0.25)
      (net 29 "SD_DAT0") (pintype "passive"))
  )
)
